# S9S_MB_2U (Grand Teton) — schematic netlist excerpt (pin names and nets, part order shuffled) for the footprints in the layout excerpt that follows; sources: Cadence DE-HDL packaged netlist, KiCad conversion of 03242023_DA0F0TMBIJ0_F0T_Motherboard_J_brd_V01_OCP.brd

PC1196  Q_CAP  1UF 16V 10% X6S  pkg C0402  page 278 : A = PVCCD_HV_CPU0_VREF ; B = GND
R4134  Q_RES  100K 1% EMPTY  pkg 0402LF  page 146 : A = GPU_3V3IO_RSVD5_FFU ; B = GND

(kicad_pcb
	(version 20260206)
	(generator "pcbnew")
	(generator_version "10.0")
	(general
		(thickness 1.6)
		(legacy_teardrops no)
	)
	(paper "A4")
	(title_block
		(title "03242023_DA0F0TMBIJ0_F0T_Motherboard_J_brd_V01_OCP.brd")
		(comment 1 "Grand Teton / footprints 899-900 of 6105")
	)
	(layers
		(0 "F.Cu" signal "TOP")
		(4 "In1.Cu" signal "GND")
		(6 "In2.Cu" signal "IN1")
		(8 "In3.Cu" signal "GND1")
		(10 "In4.Cu" signal "IN2")
		(12 "In5.Cu" signal "GND2")
		(14 "In6.Cu" signal "IN3")
		(16 "In7.Cu" signal "GND3")
		(18 "In8.Cu" signal "VCC")
		(20 "In9.Cu" signal "VCC1")
		(22 "In10.Cu" signal "GND4")
		(24 "In11.Cu" signal "IN4")
		(26 "In12.Cu" signal "GND5")
		(28 "In13.Cu" signal "IN5")
		(30 "In14.Cu" signal "GND6")
		(32 "In15.Cu" signal "IN6")
		(34 "In16.Cu" signal "GND7")
		(2 "B.Cu" signal "BOTTOM")
		(9 "F.Adhes" user "F.Adhesive")
		(11 "B.Adhes" user "B.Adhesive")
		(13 "F.Paste" user "Package Geometry/Pastemask Top")
		(15 "B.Paste" user "Package Geometry/Pastemask Bottom")
		(5 "F.SilkS" user "Ref Des/Silkscreen Top")
		(7 "B.SilkS" user "Ref Des/Silkscreen Bottom")
		(1 "F.Mask" user "Board Geometry/Soldermask Top")
		(3 "B.Mask" user "Board Geometry/Soldermask Bottom")
		(17 "Dwgs.User" user "User.Drawings")
		(19 "Cmts.User" user "User.Comments")
		(21 "Eco1.User" user "User.Eco1")
		(23 "Eco2.User" user "User.Eco2")
		(25 "Edge.Cuts" user "Board Geometry/Outline")
		(27 "Margin" user)
		(31 "F.CrtYd" user "Package Geometry/Place Bound Top")
		(29 "B.CrtYd" user "Package Geometry/Place Bound Bottom")
		(35 "F.Fab" user "Ref Des/Assembly Top")
		(33 "B.Fab" user "Ref Des/Assembly Bottom")
	)
	(footprint ""
		(layer "F.Cu")
		(at 431.202592 -118.815104 -90)
		(property "Reference" "PC1196"
			(at 0 0 270)
			(layer "F.SilkS")
			(hide yes)
			(effects
				(font
					(size 1.27 1.27)
				)
			)
		)
		(property "Value" ""
			(at 0 0 270)
			(layer "F.Fab")
			(effects
				(font
					(size 1.27 1.27)
				)
			)
		)
		(duplicate_pad_numbers_are_jumpers no)
		(fp_line
			(start -0.7874 0.4064)
			(end -0.7874 -0.4064)
			(stroke
				(width 0.1524)
				(type default)
			)
			(layer "F.SilkS")
		)
		(fp_line
			(start 0.7874 0.4064)
			(end -0.7874 0.4064)
			(stroke
				(width 0.1524)
				(type default)
			)
			(layer "F.SilkS")
		)
		(fp_line
			(start -0.7874 -0.4064)
			(end 0.7874 -0.4064)
			(stroke
				(width 0.1524)
				(type default)
			)
			(layer "F.SilkS")
		)
		(fp_line
			(start 0.7874 -0.4064)
			(end 0.7874 0.4064)
			(stroke
				(width 0.1524)
				(type default)
			)
			(layer "F.SilkS")
		)
		(fp_line
			(start -0.67945 0.3048)
			(end -0.67945 -0.305054)
			(stroke
				(width 0.1)
				(type default)
			)
			(layer "F.Fab")
		)
		(fp_line
			(start -0.12065 0.3048)
			(end -0.67945 0.3048)
			(stroke
				(width 0.1)
				(type default)
			)
			(layer "F.Fab")
		)
		(fp_line
			(start 0.120396 0.3048)
			(end 0.120396 0.2794)
			(stroke
				(width 0.1)
				(type default)
			)
			(layer "F.Fab")
		)
		(fp_line
			(start 0.67945 0.3048)
			(end 0.120396 0.3048)
			(stroke
				(width 0.1)
				(type default)
			)
			(layer "F.Fab")
		)
		(fp_line
			(start -0.12065 0.2794)
			(end -0.12065 0.3048)
			(stroke
				(width 0.1)
				(type default)
			)
			(layer "F.Fab")
		)
		(fp_line
			(start 0.120396 0.2794)
			(end -0.12065 0.2794)
			(stroke
				(width 0.1)
				(type default)
			)
			(layer "F.Fab")
		)
		(fp_line
			(start -0.12065 -0.2794)
			(end 0.12065 -0.2794)
			(stroke
				(width 0.1)
				(type default)
			)
			(layer "F.Fab")
		)
		(fp_line
			(start 0.12065 -0.2794)
			(end 0.12065 -0.3048)
			(stroke
				(width 0.1)
				(type default)
			)
			(layer "F.Fab")
		)
		(fp_line
			(start 0.12065 -0.3048)
			(end 0.67945 -0.3048)
			(stroke
				(width 0.1)
				(type default)
			)
			(layer "F.Fab")
		)
		(fp_line
			(start 0.67945 -0.3048)
			(end 0.67945 0.3048)
			(stroke
				(width 0.1)
				(type default)
			)
			(layer "F.Fab")
		)
		(fp_line
			(start -0.67945 -0.305054)
			(end -0.12065 -0.305054)
			(stroke
				(width 0.1)
				(type default)
			)
			(layer "F.Fab")
		)
		(fp_line
			(start -0.12065 -0.305054)
			(end -0.12065 -0.2794)
			(stroke
				(width 0.1)
				(type default)
			)
			(layer "F.Fab")
		)
		(pad "1" smd circle
			(at -0.40005 0 270)
			(size 0 0)
			(layers "F.Cu" "F.Mask" "F.Paste")
			(net "PVCCD_HV_CPU0_VREF")
		)
		(pad "2" smd circle
			(at 0.40005 0 270)
			(size 0 0)
			(layers "F.Cu" "F.Mask" "F.Paste")
			(net "GND")
		)
	)
	(footprint ""
		(layer "F.Cu")
		(at 297.41622 -419.02761 -90)
		(property "Reference" "R4134"
			(at 0 0 270)
			(layer "F.SilkS")
			(hide yes)
			(effects
				(font
					(size 1.27 1.27)
				)
			)
		)
		(property "Value" ""
			(at 0 0 270)
			(layer "F.Fab")
			(effects
				(font
					(size 1.27 1.27)
				)
			)
		)
		(duplicate_pad_numbers_are_jumpers no)
		(fp_line
			(start -0.7874 0.4064)
			(end -0.7874 -0.4064)
			(stroke
				(width 0.1524)
				(type default)
			)
			(layer "F.SilkS")
		)
		(fp_line
			(start 0.7874 0.4064)
			(end -0.7874 0.4064)
			(stroke
				(width 0.1524)
				(type default)
			)
			(layer "F.SilkS")
		)
		(fp_line
			(start -0.7874 -0.4064)
			(end 0.7874 -0.4064)
			(stroke
				(width 0.1524)
				(type default)
			)
			(layer "F.SilkS")
		)
		(fp_line
			(start 0.7874 -0.4064)
			(end 0.7874 0.4064)
			(stroke
				(width 0.1524)
				(type default)
			)
			(layer "F.SilkS")
		)
		(fp_line
			(start -0.67945 0.3048)
			(end -0.67945 -0.305054)
			(stroke
				(width 0.1)
				(type default)
			)
			(layer "F.Fab")
		)
		(fp_line
			(start -0.12065 0.3048)
			(end -0.67945 0.3048)
			(stroke
				(width 0.1)
				(type default)
			)
			(layer "F.Fab")
		)
		(fp_line
			(start 0.120396 0.3048)
			(end 0.120396 0.2794)
			(stroke
				(width 0.1)
				(type default)
			)
			(layer "F.Fab")
		)
		(fp_line
			(start 0.67945 0.3048)
			(end 0.120396 0.3048)
			(stroke
				(width 0.1)
				(type default)
			)
			(layer "F.Fab")
		)
		(fp_line
			(start -0.12065 0.2794)
			(end -0.12065 0.3048)
			(stroke
				(width 0.1)
				(type default)
			)
			(layer "F.Fab")
		)
		(fp_line
			(start 0.120396 0.2794)
			(end -0.12065 0.2794)
			(stroke
				(width 0.1)
				(type default)
			)
			(layer "F.Fab")
		)
		(fp_line
			(start -0.12065 -0.2794)
			(end 0.12065 -0.2794)
			(stroke
				(width 0.1)
				(type default)
			)
			(layer "F.Fab")
		)
		(fp_line
			(start 0.12065 -0.2794)
			(end 0.12065 -0.3048)
			(stroke
				(width 0.1)
				(type default)
			)
			(layer "F.Fab")
		)
		(fp_line
			(start 0.12065 -0.3048)
			(end 0.67945 -0.3048)
			(stroke
				(width 0.1)
				(type default)
			)
			(layer "F.Fab")
		)
		(fp_line
			(start 0.67945 -0.3048)
			(end 0.67945 0.3048)
			(stroke
				(width 0.1)
				(type default)
			)
			(layer "F.Fab")
		)
		(fp_line
			(start -0.67945 -0.305054)
			(end -0.12065 -0.305054)
			(stroke
				(width 0.1)
				(type default)
			)
			(layer "F.Fab")
		)
		(fp_line
			(start -0.12065 -0.305054)
			(end -0.12065 -0.2794)
			(stroke
				(width 0.1)
				(type default)
			)
			(layer "F.Fab")
		)
		(pad "1" smd circle
			(at -0.40005 0 270)
			(size 0 0)
			(layers "F.Cu" "F.Mask" "F.Paste")
			(net "GPU_3V3IO_RSVD5_FFU")
		)
		(pad "2" smd circle
			(at 0.40005 0 270)
			(size 0 0)
			(layers "F.Cu" "F.Mask" "F.Paste")
			(net "GND")
		)
	)
)
